(kicad_pcb
	(version 20260206)
	(generator "pcbnew")
	(generator_version "10.0")
	(general
		(thickness 1.6)
		(legacy_teardrops no)
	)
	(paper "A4")
	(title_block
		(title "01162023_DA0F0TEBIF0_F0T_Expander_BD_F_brd_V02_OCP.brd")
		(comment 1 "Grand Teton / footprints 7579-7586 of 9728")
	)
	(layers
		(0 "F.Cu" signal "TOP")
		(4 "In1.Cu" signal "GND")
		(6 "In2.Cu" signal "VCC")
		(8 "In3.Cu" signal "VCC1")
		(10 "In4.Cu" signal "GND1")
		(12 "In5.Cu" signal "IN1")
		(14 "In6.Cu" signal "GND2")
		(16 "In7.Cu" signal "IN2")
		(18 "In8.Cu" signal "GND3")
		(20 "In9.Cu" signal "IN3")
		(22 "In10.Cu" signal "GND4")
		(24 "In11.Cu" signal "IN4")
		(26 "In12.Cu" signal "GND5")
		(28 "In13.Cu" signal "IN5")
		(30 "In14.Cu" signal "GND6")
		(32 "In15.Cu" signal "IN6")
		(34 "In16.Cu" signal "GND7")
		(2 "B.Cu" signal "BOTTOM")
		(9 "F.Adhes" user "F.Adhesive")
		(11 "B.Adhes" user "B.Adhesive")
		(13 "F.Paste" user "Package Geometry/Pastemask Top")
		(15 "B.Paste" user "Package Geometry/Pastemask Bottom")
		(5 "F.SilkS" user "Ref Des/Silkscreen Top")
		(7 "B.SilkS" user "Ref Des/Silkscreen Bottom")
		(1 "F.Mask" user "Board Geometry/Soldermask Top")
		(3 "B.Mask" user "Board Geometry/Soldermask Bottom")
		(17 "Dwgs.User" user "User.Drawings")
		(19 "Cmts.User" user "User.Comments")
		(21 "Eco1.User" user "User.Eco1")
		(23 "Eco2.User" user "User.Eco2")
		(25 "Edge.Cuts" user "Board Geometry/Outline")
		(27 "Margin" user)
		(31 "F.CrtYd" user "Package Geometry/Place Bound Top")
		(29 "B.CrtYd" user "Package Geometry/Place Bound Bottom")
		(35 "F.Fab" user "Ref Des/Assembly Top")
		(33 "B.Fab" user "Ref Des/Assembly Bottom")
	)
	(footprint ""
		(layer "B.Cu")
		(at 298.974764 -297.79976 -90)
		(property "Reference" "C1695"
			(at 0 0 90)
			(layer "B.SilkS")
			(hide yes)
			(effects
				(font
					(size 1.27 1.27)
				)
				(justify mirror)
			)
		)
		(property "Value" ""
			(at 0 0 90)
			(layer "B.Fab")
			(effects
				(font
					(size 1.27 1.27)
				)
				(justify mirror)
			)
		)
		(duplicate_pad_numbers_are_jumpers no)
		(fp_line
			(start -0.299974 0.150114)
			(end 0.299974 0.150114)
			(stroke
				(width 0.1)
				(type default)
			)
			(layer "B.Fab")
		)
		(fp_line
			(start 0.299974 0.150114)
			(end 0.299974 -0.150114)
			(stroke
				(width 0.1)
				(type default)
			)
			(layer "B.Fab")
		)
		(fp_line
			(start -0.299974 -0.150114)
			(end -0.299974 0.150114)
			(stroke
				(width 0.1)
				(type default)
			)
			(layer "B.Fab")
		)
		(fp_line
			(start 0.299974 -0.150114)
			(end -0.299974 -0.150114)
			(stroke
				(width 0.1)
				(type default)
			)
			(layer "B.Fab")
		)
		(pad "1" smd rect
			(at 0.2667 0 90)
			(size 0.3048 0.381)
			(layers "B.Cu" "B.Mask" "B.Paste")
			(net "P0V8_SERDES_VDDA_PEX2")
		)
		(pad "2" smd rect
			(at -0.2667 0 90)
			(size 0.3048 0.381)
			(layers "B.Cu" "B.Mask" "B.Paste")
			(net "GND")
		)
	)
	(footprint ""
		(layer "B.Cu")
		(at 185.04154 -287.824926)
		(property "Reference" "C3170"
			(at 0 0 0)
			(layer "B.SilkS")
			(hide yes)
			(effects
				(font
					(size 1.27 1.27)
				)
				(justify mirror)
			)
		)
		(property "Value" ""
			(at 0 0 0)
			(layer "B.Fab")
			(effects
				(font
					(size 1.27 1.27)
				)
				(justify mirror)
			)
		)
		(duplicate_pad_numbers_are_jumpers no)
		(fp_line
			(start -0.299974 -0.150114)
			(end -0.299974 0.150114)
			(stroke
				(width 0.1)
				(type default)
			)
			(layer "B.Fab")
		)
		(fp_line
			(start -0.299974 0.150114)
			(end 0.299974 0.150114)
			(stroke
				(width 0.1)
				(type default)
			)
			(layer "B.Fab")
		)
		(fp_line
			(start 0.299974 -0.150114)
			(end -0.299974 -0.150114)
			(stroke
				(width 0.1)
				(type default)
			)
			(layer "B.Fab")
		)
		(fp_line
			(start 0.299974 0.150114)
			(end 0.299974 -0.150114)
			(stroke
				(width 0.1)
				(type default)
			)
			(layer "B.Fab")
		)
		(pad "1" smd rect
			(at 0.2667 0 180)
			(size 0.3048 0.381)
			(layers "B.Cu" "B.Mask" "B.Paste")
			(net "P1V8_VDDA_PEX1")
		)
		(pad "2" smd rect
			(at -0.2667 0 180)
			(size 0.3048 0.381)
			(layers "B.Cu" "B.Mask" "B.Paste")
			(net "GND")
		)
	)
	(footprint ""
		(layer "B.Cu")
		(at 208.196942 -259.311648 90)
		(property "Reference" "R6346"
			(at 0 0 90)
			(layer "B.SilkS")
			(hide yes)
			(effects
				(font
					(size 1.27 1.27)
				)
				(justify mirror)
			)
		)
		(property "Value" ""
			(at 0 0 90)
			(layer "B.Fab")
			(effects
				(font
					(size 1.27 1.27)
				)
				(justify mirror)
			)
		)
		(duplicate_pad_numbers_are_jumpers no)
		(fp_line
			(start 0.7874 -0.4064)
			(end -0.7874 -0.4064)
			(stroke
				(width 0.1524)
				(type default)
			)
			(layer "B.SilkS")
		)
		(fp_line
			(start -0.7874 -0.4064)
			(end -0.7874 0.4064)
			(stroke
				(width 0.1524)
				(type default)
			)
			(layer "B.SilkS")
		)
		(fp_line
			(start 0.7874 0.4064)
			(end 0.7874 -0.4064)
			(stroke
				(width 0.1524)
				(type default)
			)
			(layer "B.SilkS")
		)
		(fp_line
			(start -0.7874 0.4064)
			(end 0.7874 0.4064)
			(stroke
				(width 0.1524)
				(type default)
			)
			(layer "B.SilkS")
		)
		(fp_line
			(start 0.67945 -0.305054)
			(end 0.12065 -0.305054)
			(stroke
				(width 0.1)
				(type default)
			)
			(layer "B.Fab")
		)
		(fp_line
			(start 0.12065 -0.305054)
			(end 0.12065 -0.2794)
			(stroke
				(width 0.1)
				(type default)
			)
			(layer "B.Fab")
		)
		(fp_line
			(start -0.12065 -0.3048)
			(end -0.67945 -0.3048)
			(stroke
				(width 0.1)
				(type default)
			)
			(layer "B.Fab")
		)
		(fp_line
			(start -0.67945 -0.3048)
			(end -0.67945 0.3048)
			(stroke
				(width 0.1)
				(type default)
			)
			(layer "B.Fab")
		)
		(fp_line
			(start 0.12065 -0.2794)
			(end -0.12065 -0.2794)
			(stroke
				(width 0.1)
				(type default)
			)
			(layer "B.Fab")
		)
		(fp_line
			(start -0.12065 -0.2794)
			(end -0.12065 -0.3048)
			(stroke
				(width 0.1)
				(type default)
			)
			(layer "B.Fab")
		)
		(fp_line
			(start 0.12065 0.2794)
			(end 0.12065 0.3048)
			(stroke
				(width 0.1)
				(type default)
			)
			(layer "B.Fab")
		)
		(fp_line
			(start -0.120396 0.2794)
			(end 0.12065 0.2794)
			(stroke
				(width 0.1)
				(type default)
			)
			(layer "B.Fab")
		)
		(fp_line
			(start 0.67945 0.3048)
			(end 0.67945 -0.305054)
			(stroke
				(width 0.1)
				(type default)
			)
			(layer "B.Fab")
		)
		(fp_line
			(start 0.12065 0.3048)
			(end 0.67945 0.3048)
			(stroke
				(width 0.1)
				(type default)
			)
			(layer "B.Fab")
		)
		(fp_line
			(start -0.120396 0.3048)
			(end -0.120396 0.2794)
			(stroke
				(width 0.1)
				(type default)
			)
			(layer "B.Fab")
		)
		(fp_line
			(start -0.67945 0.3048)
			(end -0.120396 0.3048)
			(stroke
				(width 0.1)
				(type default)
			)
			(layer "B.Fab")
		)
		(pad "1" smd circle
			(at 0.40005 0 270)
			(size 0 0)
			(layers "B.Cu" "B.Mask" "B.Paste")
			(net "P1V8_PEX")
		)
		(pad "2" smd circle
			(at -0.40005 0 270)
			(size 0 0)
			(layers "B.Cu" "B.Mask" "B.Paste")
			(net "SMB_PEX2_MUX_SDA")
		)
	)
	(footprint ""
		(layer "B.Cu")
		(at 136.078214 -201.332846)
		(property "Reference" "C2601"
			(at 0 0 0)
			(layer "B.SilkS")
			(hide yes)
			(effects
				(font
					(size 1.27 1.27)
				)
				(justify mirror)
			)
		)
		(property "Value" ""
			(at 0 0 0)
			(layer "B.Fab")
			(effects
				(font
					(size 1.27 1.27)
				)
				(justify mirror)
			)
		)
		(duplicate_pad_numbers_are_jumpers no)
		(fp_line
			(start -0.7874 -0.4064)
			(end -0.7874 0.4064)
			(stroke
				(width 0.1524)
				(type default)
			)
			(layer "B.SilkS")
		)
		(fp_line
			(start -0.7874 0.4064)
			(end 0.7874 0.4064)
			(stroke
				(width 0.1524)
				(type default)
			)
			(layer "B.SilkS")
		)
		(fp_line
			(start 0.7874 -0.4064)
			(end -0.7874 -0.4064)
			(stroke
				(width 0.1524)
				(type default)
			)
			(layer "B.SilkS")
		)
		(fp_line
			(start 0.7874 0.4064)
			(end 0.7874 -0.4064)
			(stroke
				(width 0.1524)
				(type default)
			)
			(layer "B.SilkS")
		)
		(fp_line
			(start -0.67945 -0.3048)
			(end -0.67945 0.3048)
			(stroke
				(width 0.1)
				(type default)
			)
			(layer "B.Fab")
		)
		(fp_line
			(start -0.67945 0.3048)
			(end -0.120396 0.3048)
			(stroke
				(width 0.1)
				(type default)
			)
			(layer "B.Fab")
		)
		(fp_line
			(start -0.12065 -0.3048)
			(end -0.67945 -0.3048)
			(stroke
				(width 0.1)
				(type default)
			)
			(layer "B.Fab")
		)
		(fp_line
			(start -0.12065 -0.2794)
			(end -0.12065 -0.3048)
			(stroke
				(width 0.1)
				(type default)
			)
			(layer "B.Fab")
		)
		(fp_line
			(start -0.120396 0.2794)
			(end 0.12065 0.2794)
			(stroke
				(width 0.1)
				(type default)
			)
			(layer "B.Fab")
		)
		(fp_line
			(start -0.120396 0.3048)
			(end -0.120396 0.2794)
			(stroke
				(width 0.1)
				(type default)
			)
			(layer "B.Fab")
		)
		(fp_line
			(start 0.12065 -0.305054)
			(end 0.12065 -0.2794)
			(stroke
				(width 0.1)
				(type default)
			)
			(layer "B.Fab")
		)
		(fp_line
			(start 0.12065 -0.2794)
			(end -0.12065 -0.2794)
			(stroke
				(width 0.1)
				(type default)
			)
			(layer "B.Fab")
		)
		(fp_line
			(start 0.12065 0.2794)
			(end 0.12065 0.3048)
			(stroke
				(width 0.1)
				(type default)
			)
			(layer "B.Fab")
		)
		(fp_line
			(start 0.12065 0.3048)
			(end 0.67945 0.3048)
			(stroke
				(width 0.1)
				(type default)
			)
			(layer "B.Fab")
		)
		(fp_line
			(start 0.67945 -0.305054)
			(end 0.12065 -0.305054)
			(stroke
				(width 0.1)
				(type default)
			)
			(layer "B.Fab")
		)
		(fp_line
			(start 0.67945 0.3048)
			(end 0.67945 -0.305054)
			(stroke
				(width 0.1)
				(type default)
			)
			(layer "B.Fab")
		)
		(pad "1" smd circle
			(at 0.40005 0 180)
			(size 0 0)
			(layers "B.Cu" "B.Mask" "B.Paste")
			(net "P3V3_CLI_VPHY")
		)
		(pad "2" smd circle
			(at -0.40005 0 180)
			(size 0 0)
			(layers "B.Cu" "B.Mask" "B.Paste")
			(net "GND")
		)
	)
	(footprint ""
		(layer "B.Cu")
		(at 291.46119 -203.363068)
		(property "Reference" "R1039"
			(at 0 0 0)
			(layer "B.SilkS")
			(hide yes)
			(effects
				(font
					(size 1.27 1.27)
				)
				(justify mirror)
			)
		)
		(property "Value" ""
			(at 0 0 0)
			(layer "B.Fab")
			(effects
				(font
					(size 1.27 1.27)
				)
				(justify mirror)
			)
		)
		(duplicate_pad_numbers_are_jumpers no)
		(fp_line
			(start -0.7874 -0.4064)
			(end -0.7874 0.4064)
			(stroke
				(width 0.1524)
				(type default)
			)
			(layer "B.SilkS")
		)
		(fp_line
			(start -0.7874 0.4064)
			(end 0.7874 0.4064)
			(stroke
				(width 0.1524)
				(type default)
			)
			(layer "B.SilkS")
		)
		(fp_line
			(start 0.7874 -0.4064)
			(end -0.7874 -0.4064)
			(stroke
				(width 0.1524)
				(type default)
			)
			(layer "B.SilkS")
		)
		(fp_line
			(start 0.7874 0.4064)
			(end 0.7874 -0.4064)
			(stroke
				(width 0.1524)
				(type default)
			)
			(layer "B.SilkS")
		)
		(fp_line
			(start -0.67945 -0.3048)
			(end -0.67945 0.3048)
			(stroke
				(width 0.1)
				(type default)
			)
			(layer "B.Fab")
		)
		(fp_line
			(start -0.67945 0.3048)
			(end -0.120396 0.3048)
			(stroke
				(width 0.1)
				(type default)
			)
			(layer "B.Fab")
		)
		(fp_line
			(start -0.12065 -0.3048)
			(end -0.67945 -0.3048)
			(stroke
				(width 0.1)
				(type default)
			)
			(layer "B.Fab")
		)
		(fp_line
			(start -0.12065 -0.2794)
			(end -0.12065 -0.3048)
			(stroke
				(width 0.1)
				(type default)
			)
			(layer "B.Fab")
		)
		(fp_line
			(start -0.120396 0.2794)
			(end 0.12065 0.2794)
			(stroke
				(width 0.1)
				(type default)
			)
			(layer "B.Fab")
		)
		(fp_line
			(start -0.120396 0.3048)
			(end -0.120396 0.2794)
			(stroke
				(width 0.1)
				(type default)
			)
			(layer "B.Fab")
		)
		(fp_line
			(start 0.12065 -0.305054)
			(end 0.12065 -0.2794)
			(stroke
				(width 0.1)
				(type default)
			)
			(layer "B.Fab")
		)
		(fp_line
			(start 0.12065 -0.2794)
			(end -0.12065 -0.2794)
			(stroke
				(width 0.1)
				(type default)
			)
			(layer "B.Fab")
		)
		(fp_line
			(start 0.12065 0.2794)
			(end 0.12065 0.3048)
			(stroke
				(width 0.1)
				(type default)
			)
			(layer "B.Fab")
		)
		(fp_line
			(start 0.12065 0.3048)
			(end 0.67945 0.3048)
			(stroke
				(width 0.1)
				(type default)
			)
			(layer "B.Fab")
		)
		(fp_line
			(start 0.67945 -0.305054)
			(end 0.12065 -0.305054)
			(stroke
				(width 0.1)
				(type default)
			)
			(layer "B.Fab")
		)
		(fp_line
			(start 0.67945 0.3048)
			(end 0.67945 -0.305054)
			(stroke
				(width 0.1)
				(type default)
			)
			(layer "B.Fab")
		)
		(pad "1" smd circle
			(at 0.40005 0 180)
			(size 0 0)
			(layers "B.Cu" "B.Mask" "B.Paste")
			(net "SPI_BIC1_MOSI_LS23_DIR3")
		)
		(pad "2" smd circle
			(at -0.40005 0 180)
			(size 0 0)
			(layers "B.Cu" "B.Mask" "B.Paste")
			(net "P1V8_PEX")
		)
	)
	(footprint ""
		(layer "B.Cu")
		(at 291.367718 -286.18434 90)
		(property "Reference" "C3292"
			(at 0 0 90)
			(layer "B.SilkS")
			(hide yes)
			(effects
				(font
					(size 1.27 1.27)
				)
				(justify mirror)
			)
		)
		(property "Value" ""
			(at 0 0 90)
			(layer "B.Fab")
			(effects
				(font
					(size 1.27 1.27)
				)
				(justify mirror)
			)
		)
		(duplicate_pad_numbers_are_jumpers no)
		(fp_line
			(start 1.2954 -0.5842)
			(end -1.2954 -0.5842)
			(stroke
				(width 0.1524)
				(type default)
			)
			(layer "B.SilkS")
		)
		(fp_line
			(start -1.2954 -0.5842)
			(end -1.2954 0.5842)
			(stroke
				(width 0.1524)
				(type default)
			)
			(layer "B.SilkS")
		)
		(fp_line
			(start 1.2954 0.5842)
			(end 1.2954 -0.5842)
			(stroke
				(width 0.1524)
				(type default)
			)
			(layer "B.SilkS")
		)
		(fp_line
			(start -1.2954 0.5842)
			(end 1.2954 0.5842)
			(stroke
				(width 0.1524)
				(type default)
			)
			(layer "B.SilkS")
		)
		(fp_line
			(start 0.8636 -0.4572)
			(end -0.8636 -0.4572)
			(stroke
				(width 0.1)
				(type default)
			)
			(layer "B.Fab")
		)
		(fp_line
			(start -0.8636 -0.4572)
			(end -0.8636 -0.4064)
			(stroke
				(width 0.1)
				(type default)
			)
			(layer "B.Fab")
		)
		(fp_line
			(start 1.1938 -0.4064)
			(end 0.8636 -0.4064)
			(stroke
				(width 0.1)
				(type default)
			)
			(layer "B.Fab")
		)
		(fp_line
			(start 0.8636 -0.4064)
			(end 0.8636 -0.4572)
			(stroke
				(width 0.1)
				(type default)
			)
			(layer "B.Fab")
		)
		(fp_line
			(start -0.8636 -0.4064)
			(end -1.1938 -0.4064)
			(stroke
				(width 0.1)
				(type default)
			)
			(layer "B.Fab")
		)
		(fp_line
			(start -1.1938 -0.4064)
			(end -1.1938 0.4064)
			(stroke
				(width 0.1)
				(type default)
			)
			(layer "B.Fab")
		)
		(fp_line
			(start 1.1938 0.4064)
			(end 1.1938 -0.4064)
			(stroke
				(width 0.1)
				(type default)
			)
			(layer "B.Fab")
		)
		(fp_line
			(start 0.8636 0.4064)
			(end 1.1938 0.4064)
			(stroke
				(width 0.1)
				(type default)
			)
			(layer "B.Fab")
		)
		(fp_line
			(start -0.8636 0.4064)
			(end -0.8636 0.4572)
			(stroke
				(width 0.1)
				(type default)
			)
			(layer "B.Fab")
		)
		(fp_line
			(start -1.1938 0.4064)
			(end -0.8636 0.4064)
			(stroke
				(width 0.1)
				(type default)
			)
			(layer "B.Fab")
		)
		(fp_line
			(start 0.8636 0.4572)
			(end 0.8636 0.4064)
			(stroke
				(width 0.1)
				(type default)
			)
			(layer "B.Fab")
		)
		(fp_line
			(start -0.8636 0.4572)
			(end 0.8636 0.4572)
			(stroke
				(width 0.1)
				(type default)
			)
			(layer "B.Fab")
		)
		(pad "1" smd rect
			(at 0.7366 0)
			(size 0.7112 0.8128)
			(layers "B.Cu" "B.Mask" "B.Paste")
			(net "P1V25_SERDES_VDDPLL_PEX2")
		)
		(pad "2" smd rect
			(at -0.7366 0)
			(size 0.7112 0.8128)
			(layers "B.Cu" "B.Mask" "B.Paste")
			(net "GND")
		)
	)
	(footprint ""
		(layer "B.Cu")
		(at 278.554942 -297.32478)
		(property "Reference" "C3377"
			(at 0 0 0)
			(layer "B.SilkS")
			(hide yes)
			(effects
				(font
					(size 1.27 1.27)
				)
				(justify mirror)
			)
		)
		(property "Value" ""
			(at 0 0 0)
			(layer "B.Fab")
			(effects
				(font
					(size 1.27 1.27)
				)
				(justify mirror)
			)
		)
		(duplicate_pad_numbers_are_jumpers no)
		(fp_line
			(start -0.299974 -0.150114)
			(end -0.299974 0.150114)
			(stroke
				(width 0.1)
				(type default)
			)
			(layer "B.Fab")
		)
		(fp_line
			(start -0.299974 0.150114)
			(end 0.299974 0.150114)
			(stroke
				(width 0.1)
				(type default)
			)
			(layer "B.Fab")
		)
		(fp_line
			(start 0.299974 -0.150114)
			(end -0.299974 -0.150114)
			(stroke
				(width 0.1)
				(type default)
			)
			(layer "B.Fab")
		)
		(fp_line
			(start 0.299974 0.150114)
			(end 0.299974 -0.150114)
			(stroke
				(width 0.1)
				(type default)
			)
			(layer "B.Fab")
		)
		(pad "1" smd rect
			(at 0.2667 0 180)
			(size 0.3048 0.381)
			(layers "B.Cu" "B.Mask" "B.Paste")
			(net "PCEPLL2_VDDA18_PEX2")
		)
		(pad "2" smd rect
			(at -0.2667 0 180)
			(size 0.3048 0.381)
			(layers "B.Cu" "B.Mask" "B.Paste")
			(net "GND")
		)
	)
	(footprint ""
		(layer "B.Cu")
		(at 414.599882 -301.599854 -90)
		(property "Reference" "C1937"
			(at 0 0 90)
			(layer "B.SilkS")
			(hide yes)
			(effects
				(font
					(size 1.27 1.27)
				)
				(justify mirror)
			)
		)
		(property "Value" ""
			(at 0 0 90)
			(layer "B.Fab")
			(effects
				(font
					(size 1.27 1.27)
				)
				(justify mirror)
			)
		)
		(duplicate_pad_numbers_are_jumpers no)
		(fp_line
			(start -0.299974 0.150114)
			(end 0.299974 0.150114)
			(stroke
				(width 0.1)
				(type default)
			)
			(layer "B.Fab")
		)
		(fp_line
			(start 0.299974 0.150114)
			(end 0.299974 -0.150114)
			(stroke
				(width 0.1)
				(type default)
			)
			(layer "B.Fab")
		)
		(fp_line
			(start -0.299974 -0.150114)
			(end -0.299974 0.150114)
			(stroke
				(width 0.1)
				(type default)
			)
			(layer "B.Fab")
		)
		(fp_line
			(start 0.299974 -0.150114)
			(end -0.299974 -0.150114)
			(stroke
				(width 0.1)
				(type default)
			)
			(layer "B.Fab")
		)
		(pad "1" smd rect
			(at 0.2667 0 90)
			(size 0.3048 0.381)
			(layers "B.Cu" "B.Mask" "B.Paste")
			(net "P0V8_SERDES_VDDA_PEX3")
		)
		(pad "2" smd rect
			(at -0.2667 0 90)
			(size 0.3048 0.381)
			(layers "B.Cu" "B.Mask" "B.Paste")
			(net "GND")
		)
	)
)
